#ISCELL
  mstr_misc dns *
  *
#ISCELL
  pure_quanta quanta_title_block_c *
  *
#ISCELL
  pure_quanta_power cad_note *
  *
#ISCELL
  standard offpage *
  page342_i1
#ISCELL
  pure_quanta_power universal_gnd *
  page342_i10
#ISCELL
  pure_quanta_power universal_gnd *
  page342_i11
#CELL
  pure_quanta q_cap *
  page342_i12
#ISCELL
  pure_quanta_power universal_power *
  page342_i13
#CELL
  pure_quanta 74lvc1g126se7 *
  page342_i14
#ISCELL
  standard offpage *
  page342_i15
#CELL
  pure_quanta q_cap *
  page342_i16
#ISCELL
  pure_quanta_power universal_gnd *
  page342_i17
#CELL
  pure_quanta q_res *
  page342_i18
#ISCELL
  pure_quanta_power universal_power *
  page342_i19
#ISCELL
  standard offpage *
  page342_i2
#ISCELL
  pure_quanta_power universal_power *
  page342_i20
#ISCELL
  pure_quanta_power universal_gnd *
  page342_i21
#CELL
  pure_quanta 74lvc1g07gv *
  page342_i22
#ISCELL
  pure_quanta_power universal_gnd *
  page342_i23
#CELL
  pure_quanta q_res *
  page342_i24
#CELL
  pure_quanta q_res *
  page342_i25
#ISCELL
  standard offpage *
  page342_i26
#ISCELL
  standard offpage *
  page342_i27
#ISCELL
  pure_quanta_power universal_gnd *
  page342_i28
#CELL
  pure_quanta q_res *
  page342_i29
#CELL
  pure_quanta q_res *
  page342_i3
#ISCELL
  pure_quanta_power universal_gnd *
  page342_i30
#CELL
  pure_quanta q_cap *
  page342_i31
#CELL
  pure_quanta 74lvc1g07gv *
  page342_i32
#CELL
  pure_quanta q_res *
  page342_i33
#CELL
  pure_quanta q_res *
  page342_i34
#ISCELL
  pure_quanta_power universal_power *
  page342_i35
#CELL
  pure_quanta q_res *
  page342_i36
#ISCELL
  standard offpage *
  page342_i37
#ISCELL
  pure_quanta_power universal_gnd *
  page342_i38
#ISCELL
  pure_quanta_power universal_power *
  page342_i39
#CELL
  pure_quanta q_res *
  page342_i4
#ISCELL
  pure_quanta_power universal_gnd *
  page342_i40
#CELL
  pure_quanta q_cap *
  page342_i41
#ISCELL
  standard offpage *
  page342_i42
#CELL
  pure_quanta q_res *
  page342_i43
#CELL
  pure_quanta q_res *
  page342_i44
#ISCELL
  pure_quanta_power universal_power *
  page342_i45
#ISCELL
  pure_quanta_power universal_gnd *
  page342_i46
#CELL
  pure_quanta q_cap *
  page342_i47
#ISCELL
  standard offpage *
  page342_i48
#ISCELL
  pure_quanta_power universal_power *
  page342_i49
#ISCELL
  pure_quanta_power universal_power *
  page342_i5
#ISCELL
  standard offpage *
  page342_i50
#ISCELL
  pure_quanta_power universal_power *
  page342_i51
#ISCELL
  standard offpage *
  page342_i53
#ISCELL
  pure_quanta_power universal_gnd *
  page342_i54
#CELL
  pure_quanta q_cap *
  page342_i55
#ISCELL
  pure_quanta_power universal_gnd *
  page342_i56
#ISCELL
  pure_quanta_power universal_power *
  page342_i57
#CELL
  pure_quanta 74lvc1g17gw *
  page342_i58
#CELL
  pure_quanta q_res *
  page342_i6
#ISCELL
  standard offpage *
  page342_i68
#ISCELL
  standard offpage *
  page342_i69
#ISCELL
  standard offpage *
  page342_i7
#ISCELL
  standard offpage *
  page342_i70
#ISCELL
  standard offpage *
  page342_i71
#CELL
  pure_quanta q_res *
  page342_i72
#CELL
  pure_quanta q_res *
  page342_i73
#CELL
  pure_quanta q_res *
  page342_i74
#CELL
  pure_quanta q_res *
  page342_i75
#CELL
  pure_quanta 74lvc1g66gv *
  page342_i76
#ISCELL
  pure_quanta_power universal_gnd *
  page342_i8
#CELL
  pure_quanta 74lvc1g126se7 *
  page342_i9
